# S9S_MB_2U (Grand Teton) — schematic netlist excerpt (pin names and nets, part order shuffled) for the footprints in the layout excerpt that follows; sources: Cadence DE-HDL packaged netlist, KiCad conversion of 03242023_DA0F0TMBIJ0_F0T_Motherboard_J_brd_V01_OCP.brd

PC403_P1_1  Q_CAP  22UF 16V 20% X6S  pkg C0805  page 289 : A = SW_P12V_PVCCFA_EHV_FIVRA_CPU1_R ; B = GND
C208  Q_CAP  10UF 6.3V 20% X6S  pkg C0603  page 206 : A = P3V3_DB2000_VDDR ; B = GND
R905  Q_RES  33.2 1% CHIP  pkg 0402LF  page 114 : A = PWRGD_CHG_CPU1_DIMM1 ; B = PWRGD_FAIL_CPU1_GH

(kicad_pcb
	(version 20260206)
	(generator "pcbnew")
	(generator_version "10.0")
	(general
		(thickness 1.6)
		(legacy_teardrops no)
	)
	(paper "A4")
	(title_block
		(title "03242023_DA0F0TMBIJ0_F0T_Motherboard_J_brd_V01_OCP.brd")
		(comment 1 "Grand Teton / footprints 5728-5730 of 6105")
	)
	(layers
		(0 "F.Cu" signal "TOP")
		(4 "In1.Cu" signal "GND")
		(6 "In2.Cu" signal "IN1")
		(8 "In3.Cu" signal "GND1")
		(10 "In4.Cu" signal "IN2")
		(12 "In5.Cu" signal "GND2")
		(14 "In6.Cu" signal "IN3")
		(16 "In7.Cu" signal "GND3")
		(18 "In8.Cu" signal "VCC")
		(20 "In9.Cu" signal "VCC1")
		(22 "In10.Cu" signal "GND4")
		(24 "In11.Cu" signal "IN4")
		(26 "In12.Cu" signal "GND5")
		(28 "In13.Cu" signal "IN5")
		(30 "In14.Cu" signal "GND6")
		(32 "In15.Cu" signal "IN6")
		(34 "In16.Cu" signal "GND7")
		(2 "B.Cu" signal "BOTTOM")
		(9 "F.Adhes" user "F.Adhesive")
		(11 "B.Adhes" user "B.Adhesive")
		(13 "F.Paste" user "Package Geometry/Pastemask Top")
		(15 "B.Paste" user "Package Geometry/Pastemask Bottom")
		(5 "F.SilkS" user "Ref Des/Silkscreen Top")
		(7 "B.SilkS" user "Ref Des/Silkscreen Bottom")
		(1 "F.Mask" user "Board Geometry/Soldermask Top")
		(3 "B.Mask" user "Board Geometry/Soldermask Bottom")
		(17 "Dwgs.User" user "User.Drawings")
		(19 "Cmts.User" user "User.Comments")
		(21 "Eco1.User" user "User.Eco1")
		(23 "Eco2.User" user "User.Eco2")
		(25 "Edge.Cuts" user "Board Geometry/Outline")
		(27 "Margin" user)
		(31 "F.CrtYd" user "Package Geometry/Place Bound Top")
		(29 "B.CrtYd" user "Package Geometry/Place Bound Bottom")
		(35 "F.Fab" user "Ref Des/Assembly Top")
		(33 "B.Fab" user "Ref Des/Assembly Bottom")
	)
	(footprint ""
		(layer "B.Cu")
		(at 237.488476 -121.236994 180)
		(property "Reference" "C208"
			(at 0 0 0)
			(layer "B.SilkS")
			(hide yes)
			(effects
				(font
					(size 1.27 1.27)
				)
				(justify mirror)
			)
		)
		(property "Value" ""
			(at 0 0 0)
			(layer "B.Fab")
			(effects
				(font
					(size 1.27 1.27)
				)
				(justify mirror)
			)
		)
		(duplicate_pad_numbers_are_jumpers no)
		(fp_line
			(start 1.2954 0.5842)
			(end 1.2954 -0.5842)
			(stroke
				(width 0.1524)
				(type default)
			)
			(layer "B.SilkS")
		)
		(fp_line
			(start 1.2954 -0.5842)
			(end -1.2954 -0.5842)
			(stroke
				(width 0.1524)
				(type default)
			)
			(layer "B.SilkS")
		)
		(fp_line
			(start 0 -0.5842)
			(end 0 0.5842)
			(stroke
				(width 0.1524)
				(type default)
			)
			(layer "B.SilkS")
		)
		(fp_line
			(start -1.2954 0.5842)
			(end 1.2954 0.5842)
			(stroke
				(width 0.1524)
				(type default)
			)
			(layer "B.SilkS")
		)
		(fp_line
			(start -1.2954 -0.5842)
			(end -1.2954 0.5842)
			(stroke
				(width 0.1524)
				(type default)
			)
			(layer "B.SilkS")
		)
		(fp_line
			(start 1.1938 0.4064)
			(end 1.1938 -0.4064)
			(stroke
				(width 0.1)
				(type default)
			)
			(layer "B.Fab")
		)
		(fp_line
			(start 1.1938 -0.4064)
			(end 0.8636 -0.4064)
			(stroke
				(width 0.1)
				(type default)
			)
			(layer "B.Fab")
		)
		(fp_line
			(start 0.8636 0.4572)
			(end 0.8636 0.4064)
			(stroke
				(width 0.1)
				(type default)
			)
			(layer "B.Fab")
		)
		(fp_line
			(start 0.8636 0.4064)
			(end 1.1938 0.4064)
			(stroke
				(width 0.1)
				(type default)
			)
			(layer "B.Fab")
		)
		(fp_line
			(start 0.8636 -0.4064)
			(end 0.8636 -0.4572)
			(stroke
				(width 0.1)
				(type default)
			)
			(layer "B.Fab")
		)
		(fp_line
			(start 0.8636 -0.4572)
			(end -0.8636 -0.4572)
			(stroke
				(width 0.1)
				(type default)
			)
			(layer "B.Fab")
		)
		(fp_line
			(start -0.8636 0.4572)
			(end 0.8636 0.4572)
			(stroke
				(width 0.1)
				(type default)
			)
			(layer "B.Fab")
		)
		(fp_line
			(start -0.8636 0.4064)
			(end -0.8636 0.4572)
			(stroke
				(width 0.1)
				(type default)
			)
			(layer "B.Fab")
		)
		(fp_line
			(start -0.8636 -0.4064)
			(end -1.1938 -0.4064)
			(stroke
				(width 0.1)
				(type default)
			)
			(layer "B.Fab")
		)
		(fp_line
			(start -0.8636 -0.4572)
			(end -0.8636 -0.4064)
			(stroke
				(width 0.1)
				(type default)
			)
			(layer "B.Fab")
		)
		(fp_line
			(start -1.1938 0.4064)
			(end -0.8636 0.4064)
			(stroke
				(width 0.1)
				(type default)
			)
			(layer "B.Fab")
		)
		(fp_line
			(start -1.1938 -0.4064)
			(end -1.1938 0.4064)
			(stroke
				(width 0.1)
				(type default)
			)
			(layer "B.Fab")
		)
		(pad "1" smd rect
			(at 0.7366 0 90)
			(size 0.7112 0.8128)
			(layers "B.Cu" "B.Mask" "B.Paste")
			(net "P3V3_DB2000_VDDR")
		)
		(pad "2" smd rect
			(at -0.7366 0 90)
			(size 0.7112 0.8128)
			(layers "B.Cu" "B.Mask" "B.Paste")
			(net "GND")
		)
	)
	(footprint ""
		(layer "B.Cu")
		(at 201.08799 -318.997076 90)
		(property "Reference" "R905"
			(at 0 0 90)
			(layer "B.SilkS")
			(hide yes)
			(effects
				(font
					(size 1.27 1.27)
				)
				(justify mirror)
			)
		)
		(property "Value" ""
			(at 0 0 90)
			(layer "B.Fab")
			(effects
				(font
					(size 1.27 1.27)
				)
				(justify mirror)
			)
		)
		(duplicate_pad_numbers_are_jumpers no)
		(fp_line
			(start 0.7874 -0.4064)
			(end -0.7874 -0.4064)
			(stroke
				(width 0.1524)
				(type default)
			)
			(layer "B.SilkS")
		)
		(fp_line
			(start -0.7874 -0.4064)
			(end -0.7874 0.4064)
			(stroke
				(width 0.1524)
				(type default)
			)
			(layer "B.SilkS")
		)
		(fp_line
			(start 0.7874 0.4064)
			(end 0.7874 -0.4064)
			(stroke
				(width 0.1524)
				(type default)
			)
			(layer "B.SilkS")
		)
		(fp_line
			(start -0.7874 0.4064)
			(end 0.7874 0.4064)
			(stroke
				(width 0.1524)
				(type default)
			)
			(layer "B.SilkS")
		)
		(fp_line
			(start 0.67945 -0.305054)
			(end 0.12065 -0.305054)
			(stroke
				(width 0.1)
				(type default)
			)
			(layer "B.Fab")
		)
		(fp_line
			(start 0.12065 -0.305054)
			(end 0.12065 -0.2794)
			(stroke
				(width 0.1)
				(type default)
			)
			(layer "B.Fab")
		)
		(fp_line
			(start -0.12065 -0.3048)
			(end -0.67945 -0.3048)
			(stroke
				(width 0.1)
				(type default)
			)
			(layer "B.Fab")
		)
		(fp_line
			(start -0.67945 -0.3048)
			(end -0.67945 0.3048)
			(stroke
				(width 0.1)
				(type default)
			)
			(layer "B.Fab")
		)
		(fp_line
			(start 0.12065 -0.2794)
			(end -0.12065 -0.2794)
			(stroke
				(width 0.1)
				(type default)
			)
			(layer "B.Fab")
		)
		(fp_line
			(start -0.12065 -0.2794)
			(end -0.12065 -0.3048)
			(stroke
				(width 0.1)
				(type default)
			)
			(layer "B.Fab")
		)
		(fp_line
			(start 0.12065 0.2794)
			(end 0.12065 0.3048)
			(stroke
				(width 0.1)
				(type default)
			)
			(layer "B.Fab")
		)
		(fp_line
			(start -0.120396 0.2794)
			(end 0.12065 0.2794)
			(stroke
				(width 0.1)
				(type default)
			)
			(layer "B.Fab")
		)
		(fp_line
			(start 0.67945 0.3048)
			(end 0.67945 -0.305054)
			(stroke
				(width 0.1)
				(type default)
			)
			(layer "B.Fab")
		)
		(fp_line
			(start 0.12065 0.3048)
			(end 0.67945 0.3048)
			(stroke
				(width 0.1)
				(type default)
			)
			(layer "B.Fab")
		)
		(fp_line
			(start -0.120396 0.3048)
			(end -0.120396 0.2794)
			(stroke
				(width 0.1)
				(type default)
			)
			(layer "B.Fab")
		)
		(fp_line
			(start -0.67945 0.3048)
			(end -0.120396 0.3048)
			(stroke
				(width 0.1)
				(type default)
			)
			(layer "B.Fab")
		)
		(pad "1" smd circle
			(at 0.40005 0 270)
			(size 0 0)
			(layers "B.Cu" "B.Mask" "B.Paste")
			(net "PWRGD_CHG_CPU1_DIMM1")
		)
		(pad "2" smd circle
			(at -0.40005 0 270)
			(size 0 0)
			(layers "B.Cu" "B.Mask" "B.Paste")
			(net "PWRGD_FAIL_CPU1_GH")
		)
	)
	(footprint ""
		(layer "B.Cu")
		(at 173.145958 -353.599242 90)
		(property "Reference" "PC403_P1_1"
			(at 0 0 90)
			(layer "B.SilkS")
			(hide yes)
			(effects
				(font
					(size 1.27 1.27)
				)
				(justify mirror)
			)
		)
		(property "Value" ""
			(at 0 0 90)
			(layer "B.Fab")
			(effects
				(font
					(size 1.27 1.27)
				)
				(justify mirror)
			)
		)
		(duplicate_pad_numbers_are_jumpers no)
		(fp_line
			(start 1.524 -0.762)
			(end -1.524 -0.762)
			(stroke
				(width 0.1524)
				(type default)
			)
			(layer "B.SilkS")
		)
		(fp_line
			(start -1.524 -0.762)
			(end -1.524 0.762)
			(stroke
				(width 0.1524)
				(type default)
			)
			(layer "B.SilkS")
		)
		(fp_line
			(start 1.524 0.762)
			(end 1.524 -0.762)
			(stroke
				(width 0.1524)
				(type default)
			)
			(layer "B.SilkS")
		)
		(fp_line
			(start -1.524 0.762)
			(end 1.524 0.762)
			(stroke
				(width 0.1524)
				(type default)
			)
			(layer "B.SilkS")
		)
		(fp_line
			(start 1.1049 -0.724916)
			(end 1.1049 0.724916)
			(stroke
				(width 0.1)
				(type default)
			)
			(layer "B.Fab")
		)
		(fp_line
			(start -1.1049 -0.724916)
			(end 1.1049 -0.724916)
			(stroke
				(width 0.1)
				(type default)
			)
			(layer "B.Fab")
		)
		(fp_line
			(start 1.1049 0.724916)
			(end -1.1049 0.724916)
			(stroke
				(width 0.1)
				(type default)
			)
			(layer "B.Fab")
		)
		(fp_line
			(start -1.1049 0.724916)
			(end -1.1049 -0.724916)
			(stroke
				(width 0.1)
				(type default)
			)
			(layer "B.Fab")
		)
		(pad "1" smd rect
			(at 0.889 0 90)
			(size 1.016 1.27)
			(layers "B.Cu" "B.Mask" "B.Paste")
			(net "SW_P12V_PVCCFA_EHV_FIVRA_CPU1_R")
		)
		(pad "2" smd rect
			(at -0.889 0 90)
			(size 1.016 1.27)
			(layers "B.Cu" "B.Mask" "B.Paste")
			(net "GND")
		)
	)
)
